FILE_TYPE = CONNECTIVITY;
{Allegro Design Entry HDL 17.2-2016 S081 (4005846) 1/11/2022}
"PAGE_NUMBER" = 10;
0"NC";
END.
